# TIMECARD (Time Appliance Project (Time Card)) — schematic netlist excerpt (pin names and nets, part order shuffled) for the footprints in the layout excerpt that follows; sources: Cadence DE-HDL packaged netlist, KiCad conversion of R4006-B0001-02_R01.brd

R239  RESISTOR  150OHM 1%  pkg SMC_0402R_H016  page 15 : \1\ = OSC_200M_CLKN ; \2\ = SG
C249  CAPACITOR  0.1UF 25V 10%  pkg SMC_0402R_H022  page 15 : \1\ = VDD3V3_OSC_125M ; \2\ = SG

(kicad_pcb
	(version 20260206)
	(generator "pcbnew")
	(generator_version "10.0")
	(general
		(thickness 1.6)
		(legacy_teardrops no)
	)
	(paper "A4")
	(title_block
		(title "timecard-production-celestica-r4006 — R4006-B0001-02_R01.brd")
		(comment 1 "Time Appliance Project (Time Card) / footprints 270-271 of 1113")
	)
	(layers
		(0 "F.Cu" signal "TOP")
		(4 "In1.Cu" signal "L02_GND1")
		(6 "In2.Cu" signal "L03_SIG1")
		(8 "In3.Cu" signal "L04_GND2")
		(10 "In4.Cu" signal "L05_VCC1")
		(12 "In5.Cu" signal "L06_VCC2")
		(14 "In6.Cu" signal "L07_GND3")
		(16 "In7.Cu" signal "L08_SIG2")
		(18 "In8.Cu" signal "L09_GND4")
		(2 "B.Cu" signal "BOTTOM")
		(9 "F.Adhes" user "F.Adhesive")
		(11 "B.Adhes" user "B.Adhesive")
		(13 "F.Paste" user "Package Geometry/Pastemask Top")
		(15 "B.Paste" user "Package Geometry/Pastemask Bottom")
		(5 "F.SilkS" user "Ref Des/Silkscreen Top")
		(7 "B.SilkS" user "Ref Des/Silkscreen Bottom")
		(1 "F.Mask" user "Board Geometry/Soldermask Top")
		(3 "B.Mask" user "Board Geometry/Soldermask Bottom")
		(17 "Dwgs.User" user "User.Drawings")
		(19 "Cmts.User" user "User.Comments")
		(21 "Eco1.User" user "User.Eco1")
		(23 "Eco2.User" user "User.Eco2")
		(25 "Edge.Cuts" user "Board Geometry/Outline")
		(27 "Margin" user)
		(31 "F.CrtYd" user "Package Geometry/Place Bound Top")
		(29 "B.CrtYd" user "Package Geometry/Place Bound Bottom")
		(35 "F.Fab" user "Ref Des/Assembly Top")
		(33 "B.Fab" user "Ref Des/Assembly Bottom")
	)
	(footprint ""
		(layer "F.Cu")
		(at 98.806 -24.638)
		(property "Reference" "C249"
			(at -11.43 0.16637 0)
			(unlocked yes)
			(layer "F.SilkS")
			(effects
				(font
					(size 0.7874 0.5842)
					(thickness 0.1524)
				)
			)
		)
		(property "Value" "VAL*"
			(at 0.0762 2.067306 0)
			(unlocked yes)
			(layer "F.Fab")
			(hide yes)
			(effects
				(font
					(size 0.7874 0.5842)
					(thickness 0.1524)
				)
			)
		)
		(property "Tolerance" "TOL*"
			(at 0.0762 3.032506 0)
			(unlocked yes)
			(layer "Cmts.User")
			(hide yes)
			(effects
				(font
					(size 0.7874 0.5842)
					(thickness 0.1524)
				)
			)
		)
		(property "User Part Number" "PARTNUM*"
			(at 0.1016 4.023106 0)
			(unlocked yes)
			(layer "Cmts.User")
			(hide yes)
			(effects
				(font
					(size 0.7874 0.5842)
					(thickness 0.1524)
				)
			)
		)
		(property "Device Type" "CAPACITOR-G105-0B104-EK,0.1UF,A"
			(at 0.0508 1.127506 0)
			(unlocked yes)
			(layer "F.Fab")
			(hide yes)
			(effects
				(font
					(size 0.7874 0.5842)
					(thickness 0.1524)
				)
			)
		)
		(duplicate_pad_numbers_are_jumpers no)
		(fp_line
			(start -1.143 -0.5588)
			(end -1.143 0.5588)
			(stroke
				(width 0.1)
				(type default)
			)
			(layer "F.SilkS")
		)
		(fp_line
			(start -1.143 0.5588)
			(end 1.143 0.5588)
			(stroke
				(width 0.1)
				(type default)
			)
			(layer "F.SilkS")
		)
		(fp_line
			(start 1.143 -0.5588)
			(end -1.143 -0.5588)
			(stroke
				(width 0.1)
				(type default)
			)
			(layer "F.SilkS")
		)
		(fp_line
			(start 1.143 0.5588)
			(end 1.143 -0.5588)
			(stroke
				(width 0.1)
				(type default)
			)
			(layer "F.SilkS")
		)
		(fp_rect
			(start -1.143 0.5588)
			(end 1.143 -0.5588)
			(stroke
				(width 0)
				(type default)
			)
			(fill no)
			(layer "F.CrtYd")
		)
		(fp_line
			(start -0.508 -0.3048)
			(end -0.508 0.3048)
			(stroke
				(width 0.1)
				(type default)
			)
			(layer "F.Fab")
		)
		(fp_line
			(start -0.508 0.3048)
			(end 0.508 0.3048)
			(stroke
				(width 0.1)
				(type default)
			)
			(layer "F.Fab")
		)
		(fp_line
			(start 0.508 -0.3048)
			(end -0.508 -0.3048)
			(stroke
				(width 0.1)
				(type default)
			)
			(layer "F.Fab")
		)
		(fp_line
			(start 0.508 0.3048)
			(end 0.508 -0.3048)
			(stroke
				(width 0.1)
				(type default)
			)
			(layer "F.Fab")
		)
		(pad "1" smd rect
			(at -0.5334 0)
			(size 0.7112 0.6096)
			(layers "F.Cu" "F.Mask" "F.Paste")
			(net "VDD3V3_OSC_125M")
		)
		(pad "2" smd rect
			(at 0.5334 0)
			(size 0.7112 0.6096)
			(layers "F.Cu" "F.Mask" "F.Paste")
			(net "SG")
		)
		(zone
			(layer "F.Cu")
			(hatch none 0.5)
			(connect_pads
				(clearance 0)
			)
			(min_thickness 0.25)
			(keepout
				(tracks allowed)
				(vias not_allowed)
				(pads allowed)
				(copperpour not_allowed)
				(footprints allowed)
			)
			(placement
				(enabled no)
				(sheetname "")
			)
			(fill
				(thermal_gap 0.5)
				(thermal_bridge_width 0.5)
				(island_removal_mode 0)
			)
			(polygon
				(pts
					(xy 98.7298 -24.3332) (xy 98.8822 -24.3332) (xy 98.8822 -24.9428) (xy 98.7298 -24.9428)
				)
			)
		)
	)
	(footprint ""
		(layer "F.Cu")
		(at 110.3122 -24.7142 180)
		(property "Reference" "R239"
			(at 0.9652 -8.62457 0)
			(unlocked yes)
			(layer "F.SilkS")
			(effects
				(font
					(size 0.7874 0.5842)
					(thickness 0.1524)
				)
			)
		)
		(property "Value" "VAL*"
			(at 0.02032 2.13233 180)
			(unlocked yes)
			(layer "F.Fab")
			(hide yes)
			(effects
				(font
					(size 0.7874 0.5842)
					(thickness 0.1524)
				)
			)
		)
		(property "Device Type" "RESISTOR-G155-11500-01,150OHM,A"
			(at 0.008382 1.210564 180)
			(unlocked yes)
			(layer "F.Fab")
			(hide yes)
			(effects
				(font
					(size 0.7874 0.5842)
					(thickness 0.1524)
				)
			)
		)
		(property "User Part Number" "PARTNUM*"
			(at 0.02032 4.024884 180)
			(unlocked yes)
			(layer "Cmts.User")
			(hide yes)
			(effects
				(font
					(size 0.7874 0.5842)
					(thickness 0.1524)
				)
			)
		)
		(property "Tolerance" "TOL*"
			(at 0.044704 3.05435 180)
			(unlocked yes)
			(layer "Cmts.User")
			(hide yes)
			(effects
				(font
					(size 0.7874 0.5842)
					(thickness 0.1524)
				)
			)
		)
		(duplicate_pad_numbers_are_jumpers no)
		(fp_line
			(start 1.143 0.5588)
			(end 1.143 -0.5588)
			(stroke
				(width 0.1)
				(type default)
			)
			(layer "F.SilkS")
		)
		(fp_line
			(start 1.143 -0.5588)
			(end -1.143 -0.5588)
			(stroke
				(width 0.1)
				(type default)
			)
			(layer "F.SilkS")
		)
		(fp_line
			(start -1.143 0.5588)
			(end 1.143 0.5588)
			(stroke
				(width 0.1)
				(type default)
			)
			(layer "F.SilkS")
		)
		(fp_line
			(start -1.143 -0.5588)
			(end -1.143 0.5588)
			(stroke
				(width 0.1)
				(type default)
			)
			(layer "F.SilkS")
		)
		(fp_rect
			(start 1.143 0.5588)
			(end -1.143 -0.5588)
			(stroke
				(width 0)
				(type default)
			)
			(fill no)
			(layer "F.CrtYd")
		)
		(fp_line
			(start 0.508 0.3048)
			(end 0.508 -0.3048)
			(stroke
				(width 0.1)
				(type default)
			)
			(layer "F.Fab")
		)
		(fp_line
			(start 0.508 -0.3048)
			(end -0.508 -0.3048)
			(stroke
				(width 0.1)
				(type default)
			)
			(layer "F.Fab")
		)
		(fp_line
			(start -0.508 0.3048)
			(end 0.508 0.3048)
			(stroke
				(width 0.1)
				(type default)
			)
			(layer "F.Fab")
		)
		(fp_line
			(start -0.508 -0.3048)
			(end -0.508 0.3048)
			(stroke
				(width 0.1)
				(type default)
			)
			(layer "F.Fab")
		)
		(pad "1" smd rect
			(at -0.5334 0 180)
			(size 0.7112 0.6096)
			(layers "F.Cu" "F.Mask" "F.Paste")
			(net "OSC_200M_CLKN")
		)
		(pad "2" smd rect
			(at 0.5334 0 180)
			(size 0.7112 0.6096)
			(layers "F.Cu" "F.Mask" "F.Paste")
			(net "SG")
		)
		(zone
			(layer "F.Cu")
			(hatch none 0.5)
			(connect_pads
				(clearance 0)
			)
			(min_thickness 0.25)
			(keepout
				(tracks allowed)
				(vias not_allowed)
				(pads allowed)
				(copperpour not_allowed)
				(footprints allowed)
			)
			(placement
				(enabled no)
				(sheetname "")
			)
			(fill
				(thermal_gap 0.5)
				(thermal_bridge_width 0.5)
				(island_removal_mode 0)
			)
			(polygon
				(pts
					(xy 110.236 -25.019) (xy 110.236 -24.4094) (xy 110.3884 -24.4094) (xy 110.3884 -25.019)
				)
			)
		)
	)
)
